# T6G (Grand Teton) — schematic netlist excerpt (pin names and nets, part order shuffled) for the footprints in the layout excerpt that follows; sources: Cadence DE-HDL packaged netlist, KiCad conversion of 04192023_DAF0TMB3IC0_F0TG_MB_C_brd_V02_OCP.brd

C1080  Q_CAP  100PF 50V 5% EMPTY  pkg 0402  page 258 : A = PVDD18_S5_P0_ADC_MAM ; B = GND
PR421  Q_RES  0 5% CHIP  pkg 0402LF  page 203 : A = PVDDCR_CPU1_P0_VOS6 ; B = PVDDCR_CPU1_P0

(kicad_pcb
	(version 20260206)
	(generator "pcbnew")
	(generator_version "10.0")
	(general
		(thickness 1.6)
		(legacy_teardrops no)
	)
	(paper "A4")
	(title_block
		(title "04192023_DAF0TMB3IC0_F0TG_MB_C_brd_V02_OCP.brd")
		(comment 1 "Grand Teton / footprints 6584-6585 of 8354")
	)
	(layers
		(0 "F.Cu" signal "TOP")
		(4 "In1.Cu" signal "GND")
		(6 "In2.Cu" signal "IN1")
		(8 "In3.Cu" signal "GND1")
		(10 "In4.Cu" signal "IN2")
		(12 "In5.Cu" signal "GND2")
		(14 "In6.Cu" signal "IN3")
		(16 "In7.Cu" signal "GND3")
		(18 "In8.Cu" signal "VCC")
		(20 "In9.Cu" signal "VCC1")
		(22 "In10.Cu" signal "GND4")
		(24 "In11.Cu" signal "IN4")
		(26 "In12.Cu" signal "GND5")
		(28 "In13.Cu" signal "IN5")
		(30 "In14.Cu" signal "GND6")
		(32 "In15.Cu" signal "IN6")
		(34 "In16.Cu" signal "GND7")
		(2 "B.Cu" signal "BOTTOM")
		(9 "F.Adhes" user "F.Adhesive")
		(11 "B.Adhes" user "B.Adhesive")
		(13 "F.Paste" user "Package Geometry/Pastemask Top")
		(15 "B.Paste" user "Package Geometry/Pastemask Bottom")
		(5 "F.SilkS" user "Ref Des/Silkscreen Top")
		(7 "B.SilkS" user "Ref Des/Silkscreen Bottom")
		(1 "F.Mask" user "Board Geometry/Soldermask Top")
		(3 "B.Mask" user "Board Geometry/Soldermask Bottom")
		(17 "Dwgs.User" user "User.Drawings")
		(19 "Cmts.User" user "User.Comments")
		(21 "Eco1.User" user "User.Eco1")
		(23 "Eco2.User" user "User.Eco2")
		(25 "Edge.Cuts" user "Board Geometry/Outline")
		(27 "Margin" user)
		(31 "F.CrtYd" user "Package Geometry/Place Bound Top")
		(29 "B.CrtYd" user "Package Geometry/Place Bound Bottom")
		(35 "F.Fab" user "Ref Des/Assembly Top")
		(33 "B.Fab" user "Ref Des/Assembly Bottom")
	)
	(footprint ""
		(layer "B.Cu")
		(at 348.004638 -342.599772 -90)
		(property "Reference" "PR421"
			(at 0 0 90)
			(layer "B.SilkS")
			(hide yes)
			(effects
				(font
					(size 1.27 1.27)
				)
				(justify mirror)
			)
		)
		(property "Value" ""
			(at 0 0 90)
			(layer "B.Fab")
			(effects
				(font
					(size 1.27 1.27)
				)
				(justify mirror)
			)
		)
		(duplicate_pad_numbers_are_jumpers no)
		(fp_line
			(start -0.7874 0.4064)
			(end 0.7874 0.4064)
			(stroke
				(width 0.1524)
				(type default)
			)
			(layer "B.SilkS")
		)
		(fp_line
			(start 0.7874 0.4064)
			(end 0.7874 -0.4064)
			(stroke
				(width 0.1524)
				(type default)
			)
			(layer "B.SilkS")
		)
		(fp_line
			(start -0.7874 -0.4064)
			(end -0.7874 0.4064)
			(stroke
				(width 0.1524)
				(type default)
			)
			(layer "B.SilkS")
		)
		(fp_line
			(start 0.7874 -0.4064)
			(end -0.7874 -0.4064)
			(stroke
				(width 0.1524)
				(type default)
			)
			(layer "B.SilkS")
		)
		(fp_line
			(start -0.67945 0.3048)
			(end -0.120396 0.3048)
			(stroke
				(width 0.1)
				(type default)
			)
			(layer "B.Fab")
		)
		(fp_line
			(start -0.120396 0.3048)
			(end -0.120396 0.2794)
			(stroke
				(width 0.1)
				(type default)
			)
			(layer "B.Fab")
		)
		(fp_line
			(start 0.12065 0.3048)
			(end 0.67945 0.3048)
			(stroke
				(width 0.1)
				(type default)
			)
			(layer "B.Fab")
		)
		(fp_line
			(start 0.67945 0.3048)
			(end 0.67945 -0.305054)
			(stroke
				(width 0.1)
				(type default)
			)
			(layer "B.Fab")
		)
		(fp_line
			(start -0.120396 0.2794)
			(end 0.12065 0.2794)
			(stroke
				(width 0.1)
				(type default)
			)
			(layer "B.Fab")
		)
		(fp_line
			(start 0.12065 0.2794)
			(end 0.12065 0.3048)
			(stroke
				(width 0.1)
				(type default)
			)
			(layer "B.Fab")
		)
		(fp_line
			(start -0.12065 -0.2794)
			(end -0.12065 -0.3048)
			(stroke
				(width 0.1)
				(type default)
			)
			(layer "B.Fab")
		)
		(fp_line
			(start 0.12065 -0.2794)
			(end -0.12065 -0.2794)
			(stroke
				(width 0.1)
				(type default)
			)
			(layer "B.Fab")
		)
		(fp_line
			(start -0.67945 -0.3048)
			(end -0.67945 0.3048)
			(stroke
				(width 0.1)
				(type default)
			)
			(layer "B.Fab")
		)
		(fp_line
			(start -0.12065 -0.3048)
			(end -0.67945 -0.3048)
			(stroke
				(width 0.1)
				(type default)
			)
			(layer "B.Fab")
		)
		(fp_line
			(start 0.12065 -0.305054)
			(end 0.12065 -0.2794)
			(stroke
				(width 0.1)
				(type default)
			)
			(layer "B.Fab")
		)
		(fp_line
			(start 0.67945 -0.305054)
			(end 0.12065 -0.305054)
			(stroke
				(width 0.1)
				(type default)
			)
			(layer "B.Fab")
		)
		(pad "1" smd circle
			(at 0.40005 0 90)
			(size 0 0)
			(layers "B.Cu" "B.Mask" "B.Paste")
			(net "PVDDCR_CPU1_P0_VOS6")
		)
		(pad "2" smd circle
			(at -0.40005 0 90)
			(size 0 0)
			(layers "B.Cu" "B.Mask" "B.Paste")
			(net "PVDDCR_CPU1_P0")
		)
	)
	(footprint ""
		(layer "B.Cu")
		(at 243.713 -323.85)
		(property "Reference" "C1080"
			(at 0 0 0)
			(layer "B.SilkS")
			(hide yes)
			(effects
				(font
					(size 1.27 1.27)
				)
				(justify mirror)
			)
		)
		(property "Value" ""
			(at 0 0 0)
			(layer "B.Fab")
			(effects
				(font
					(size 1.27 1.27)
				)
				(justify mirror)
			)
		)
		(duplicate_pad_numbers_are_jumpers no)
		(fp_line
			(start -0.7874 -0.4064)
			(end -0.7874 0.4064)
			(stroke
				(width 0.1524)
				(type default)
			)
			(layer "B.SilkS")
		)
		(fp_line
			(start -0.7874 0.4064)
			(end 0.7874 0.4064)
			(stroke
				(width 0.1524)
				(type default)
			)
			(layer "B.SilkS")
		)
		(fp_line
			(start 0.7874 -0.4064)
			(end -0.7874 -0.4064)
			(stroke
				(width 0.1524)
				(type default)
			)
			(layer "B.SilkS")
		)
		(fp_line
			(start 0.7874 0.4064)
			(end 0.7874 -0.4064)
			(stroke
				(width 0.1524)
				(type default)
			)
			(layer "B.SilkS")
		)
		(fp_line
			(start -0.67945 -0.3048)
			(end -0.67945 0.3048)
			(stroke
				(width 0.1)
				(type default)
			)
			(layer "B.Fab")
		)
		(fp_line
			(start -0.67945 0.3048)
			(end -0.120396 0.3048)
			(stroke
				(width 0.1)
				(type default)
			)
			(layer "B.Fab")
		)
		(fp_line
			(start -0.12065 -0.3048)
			(end -0.67945 -0.3048)
			(stroke
				(width 0.1)
				(type default)
			)
			(layer "B.Fab")
		)
		(fp_line
			(start -0.12065 -0.2794)
			(end -0.12065 -0.3048)
			(stroke
				(width 0.1)
				(type default)
			)
			(layer "B.Fab")
		)
		(fp_line
			(start -0.120396 0.2794)
			(end 0.12065 0.2794)
			(stroke
				(width 0.1)
				(type default)
			)
			(layer "B.Fab")
		)
		(fp_line
			(start -0.120396 0.3048)
			(end -0.120396 0.2794)
			(stroke
				(width 0.1)
				(type default)
			)
			(layer "B.Fab")
		)
		(fp_line
			(start 0.12065 -0.305054)
			(end 0.12065 -0.2794)
			(stroke
				(width 0.1)
				(type default)
			)
			(layer "B.Fab")
		)
		(fp_line
			(start 0.12065 -0.2794)
			(end -0.12065 -0.2794)
			(stroke
				(width 0.1)
				(type default)
			)
			(layer "B.Fab")
		)
		(fp_line
			(start 0.12065 0.2794)
			(end 0.12065 0.3048)
			(stroke
				(width 0.1)
				(type default)
			)
			(layer "B.Fab")
		)
		(fp_line
			(start 0.12065 0.3048)
			(end 0.67945 0.3048)
			(stroke
				(width 0.1)
				(type default)
			)
			(layer "B.Fab")
		)
		(fp_line
			(start 0.67945 -0.305054)
			(end 0.12065 -0.305054)
			(stroke
				(width 0.1)
				(type default)
			)
			(layer "B.Fab")
		)
		(fp_line
			(start 0.67945 0.3048)
			(end 0.67945 -0.305054)
			(stroke
				(width 0.1)
				(type default)
			)
			(layer "B.Fab")
		)
		(pad "1" smd circle
			(at 0.40005 0 180)
			(size 0 0)
			(layers "B.Cu" "B.Mask" "B.Paste")
			(net "PVDD18_S5_P0_ADC_MAM")
		)
		(pad "2" smd circle
			(at -0.40005 0 180)
			(size 0 0)
			(layers "B.Cu" "B.Mask" "B.Paste")
			(net "GND")
		)
	)
)
